(kicad_pcb
	(version 20241229)
	(generator "pcbnew")
	(generator_version "9.0")
	(general
		(thickness 1.6296)
		(legacy_teardrops no)
	)
	(paper "A3")
	(title_block
		(title "Thunderbolt to 10GbE adapter")
		(date "2026-04-21")
		(rev "1.1.0")
		(company "Antmicro Ltd")
		(comment 1 "www.antmicro.com")
		(comment 9 "footprints 228-231 of 703")
	)
	(layers
		(0 "F.Cu" signal)
		(4 "In1.Cu" signal)
		(6 "In2.Cu" signal)
		(8 "In3.Cu" signal)
		(10 "In4.Cu" signal)
		(12 "In5.Cu" signal)
		(14 "In6.Cu" signal)
		(2 "B.Cu" signal)
		(9 "F.Adhes" user "F.Adhesive")
		(11 "B.Adhes" user "B.Adhesive")
		(13 "F.Paste" user)
		(15 "B.Paste" user)
		(5 "F.SilkS" user "F.Silkscreen")
		(7 "B.SilkS" user "B.Silkscreen")
		(1 "F.Mask" user)
		(3 "B.Mask" user)
		(17 "Dwgs.User" user "User.Drawings")
		(19 "Cmts.User" user "User.Comments")
		(21 "Eco1.User" user "User.Eco1")
		(23 "Eco2.User" user "User.Eco2")
		(25 "Edge.Cuts" user)
		(27 "Margin" user)
		(31 "F.CrtYd" user "F.Courtyard")
		(29 "B.CrtYd" user "B.Courtyard")
		(35 "F.Fab" user)
		(33 "B.Fab" user)
	)
	(footprint "antmicro-footprints:VQFN-HR-9_2x1.5mm"
		(layer "F.Cu")
		(at 146.75 110.150001)
		(property "Reference" "U13"
			(at 14.850002 17.049998 0)
			(layer "F.SilkS")
			(effects
				(font
					(size 0.7 0.7)
					(thickness 0.15)
				)
			)
		)
		(property "Value" "TPS566231P"
			(at -1.65 2.15 0)
			(layer "F.Fab")
			(effects
				(font
					(size 0.7 0.7)
					(thickness 0.15)
				)
				(justify left bottom)
			)
		)
		(property "Datasheet" "https://www.ti.com/lit/ds/symlink/tps566231.pdf"
			(at 0 -0.045 0)
			(layer "F.Fab")
			(effects
				(font
					(size 0.7 0.7)
					(thickness 0.15)
				)
				(justify left bottom)
			)
		)
		(property "Description" "Switching Voltage Regulators 3-V to 18-V, 6-A synchronous buck converter"
			(at -1.45 3.65 0)
			(layer "F.Fab")
			(effects
				(font
					(size 0.7 0.7)
					(thickness 0.15)
				)
				(justify left bottom)
			)
		)
		(property "Manufacturer" "Texas Instruments"
			(at 0 0 0)
			(unlocked yes)
			(layer "F.Fab")
			(hide yes)
			(effects
				(font
					(size 1 1)
					(thickness 0.15)
				)
			)
		)
		(property "MPN" "TPS566231PRQFR"
			(at 0 0 0)
			(unlocked yes)
			(layer "F.Fab")
			(hide yes)
			(effects
				(font
					(size 1 1)
					(thickness 0.15)
				)
			)
		)
		(property "Author" "Antmicro"
			(at 0 0 0)
			(unlocked yes)
			(layer "F.Fab")
			(hide yes)
			(effects
				(font
					(size 1 1)
					(thickness 0.15)
				)
			)
		)
		(property "License" "Apache-2.0"
			(at 0 0 0)
			(unlocked yes)
			(layer "F.Fab")
			(hide yes)
			(effects
				(font
					(size 1 1)
					(thickness 0.15)
				)
			)
		)
		(sheetname "/X710 DCDC converters/")
		(sheetfile "DCDC_converters_X710.kicad_sch")
		(attr smd)
		(fp_line
			(start -1 -0.945)
			(end -0.695 -0.945)
			(stroke
				(width 0.15)
				(type solid)
			)
			(layer "F.SilkS")
		)
		(fp_line
			(start -1 0.945)
			(end -0.695 0.945)
			(stroke
				(width 0.15)
				(type solid)
			)
			(layer "F.SilkS")
		)
		(fp_line
			(start 1 -0.945)
			(end 0.695 -0.945)
			(stroke
				(width 0.15)
				(type solid)
			)
			(layer "F.SilkS")
		)
		(fp_line
			(start 1 0.945)
			(end 0.2 0.945)
			(stroke
				(width 0.15)
				(type solid)
			)
			(layer "F.SilkS")
		)
		(fp_circle
			(center -1.18 -0.77)
			(end -1.13 -0.77)
			(stroke
				(width 0.15)
				(type solid)
			)
			(fill yes)
			(layer "F.SilkS")
		)
		(fp_rect
			(start -1.3 -1.05)
			(end 1.3 1.05)
			(stroke
				(width 0.05)
				(type solid)
			)
			(fill no)
			(layer "F.CrtYd")
		)
		(fp_rect
			(start -1 -0.75)
			(end 1 0.75)
			(stroke
				(width 0.15)
				(type solid)
			)
			(fill no)
			(layer "F.Fab")
		)
		(fp_text user "${REFERENCE}"
			(at -1.65 3.35 0)
			(layer "F.Fab")
			(effects
				(font
					(size 0.7 0.7)
					(thickness 0.15)
				)
				(justify left bottom)
			)
		)
		(fp_text user "Author: Antmicro"
			(at -1.65 4.55 0)
			(layer "F.Fab")
			(effects
				(font
					(size 0.7 0.7)
					(thickness 0.15)
				)
				(justify left bottom)
			)
		)
		(fp_text user "License: Apache-2.0"
			(at -1.65 5.75 0)
			(layer "F.Fab")
			(effects
				(font
					(size 0.7 0.7)
					(thickness 0.15)
				)
				(justify left bottom)
			)
		)
		(pad "1" smd roundrect
			(at -0.925 -0.5)
			(size 0.55 0.25)
			(layers "F.Cu" "F.Mask" "F.Paste")
			(roundrect_rratio 0.125)
			(net 116 "/X710 DCDC converters/DVDD_VCC")
			(pinfunction "V_{CC}")
			(pintype "passive")
		)
		(pad "2" smd roundrect
			(at -0.925 0)
			(size 0.55 0.25)
			(layers "F.Cu" "F.Mask" "F.Paste")
			(roundrect_rratio 0.125)
			(net 342 "/X710 DCDC converters/DVDD_FB")
			(pinfunction "FB")
			(pintype "input")
		)
		(pad "3" smd roundrect
			(at -0.925 0.5)
			(size 0.55 0.25)
			(layers "F.Cu" "F.Mask" "F.Paste")
			(roundrect_rratio 0.125)
			(net 386 "/X710 DCDC converters/DVDD_EN")
			(pinfunction "EN")
			(pintype "input")
		)
		(pad "4" smd roundrect
			(at -0.25 0.45)
			(size 0.25 1)
			(layers "F.Cu" "F.Mask" "F.Paste")
			(roundrect_rratio 0.125)
			(net 23 "GND")
			(pinfunction "PGND")
			(pintype "power_in")
		)
		(pad "5" smd roundrect
			(at 0.925 0.5)
			(size 0.55 0.25)
			(layers "F.Cu" "F.Mask" "F.Paste")
			(roundrect_rratio 0.125)
			(net 40 "+5V")
			(pinfunction "V_{IN}")
			(pintype "power_in")
		)
		(pad "6" smd roundrect
			(at 0.925 0)
			(size 0.55 0.25)
			(layers "F.Cu" "F.Mask" "F.Paste")
			(roundrect_rratio 0.125)
			(net 40 "+5V")
			(pinfunction "V_{IN}")
			(pintype "passive")
		)
		(pad "7" smd roundrect
			(at 0.925 -0.5)
			(size 0.55 0.25)
			(layers "F.Cu" "F.Mask" "F.Paste")
			(roundrect_rratio 0.125)
			(net 332 "/X710 DCDC converters/DVDD_BST")
			(pinfunction "BST")
			(pintype "passive")
		)
		(pad "8" smd roundrect
			(at 0.25 -0.3)
			(size 0.25 1.3)
			(layers "F.Cu" "F.Mask" "F.Paste")
			(roundrect_rratio 0.125)
			(net 313 "/X710 DCDC converters/DVDD_SW")
			(pinfunction "SW")
			(pintype "power_out")
		)
		(pad "9" smd roundrect
			(at -0.25 -0.675)
			(size 0.25 0.55)
			(layers "F.Cu" "F.Mask" "F.Paste")
			(roundrect_rratio 0.125)
			(net 355 "/X710 DCDC converters/DVDD_PG")
			(pinfunction "PG")
			(pintype "passive")
		)
	)
	(footprint "antmicro-footprints:C_0402_1005Metric"
		(layer "F.Cu")
		(at 168 77 -90)
		(descr "Capacitor SMD 0402")
		(tags "capacitor SMD 0402")
		(property "Reference" "C278"
			(at 3.8 -0.4 270)
			(layer "F.SilkS")
			(effects
				(font
					(size 0.7 0.7)
					(thickness 0.15)
				)
				(justify left bottom)
			)
		)
		(property "Value" "C_100n_0402"
			(at -1.022927 2.155213 270)
			(layer "F.Fab")
			(effects
				(font
					(size 0.7 0.7)
					(thickness 0.15)
				)
				(justify left bottom)
			)
		)
		(property "Datasheet" "https://www.murata.com/products/productdetail?partno=GRM155R61H104KE14%23"
			(at 0 0 270)
			(layer "F.Fab")
			(hide yes)
			(effects
				(font
					(size 1.27 1.27)
					(thickness 0.15)
				)
			)
		)
		(property "Description" "SMD Multilayer Ceramic Capacitor, 0.1 µF, 50 V, 0402 [1005 Metric], ± 10%, X5R, GRM Series"
			(at 0 0 270)
			(layer "F.Fab")
			(hide yes)
			(effects
				(font
					(size 1.27 1.27)
					(thickness 0.15)
				)
			)
		)
		(property "MPN" "GRM155R61H104KE14D"
			(at 0 0 270)
			(unlocked yes)
			(layer "F.Fab")
			(hide yes)
			(effects
				(font
					(size 1 1)
					(thickness 0.15)
				)
			)
		)
		(property "Val" "100n"
			(at 0 0 270)
			(unlocked yes)
			(layer "F.Fab")
			(hide yes)
			(effects
				(font
					(size 1 1)
					(thickness 0.15)
				)
			)
		)
		(property "Voltage" "50V"
			(at 0 0 270)
			(unlocked yes)
			(layer "F.Fab")
			(hide yes)
			(effects
				(font
					(size 1 1)
					(thickness 0.15)
				)
			)
		)
		(property "Dielectric" "X5R"
			(at 0 0 270)
			(unlocked yes)
			(layer "F.Fab")
			(hide yes)
			(effects
				(font
					(size 1 1)
					(thickness 0.15)
				)
			)
		)
		(property "Manufacturer" "Murata"
			(at 0 0 270)
			(unlocked yes)
			(layer "F.Fab")
			(hide yes)
			(effects
				(font
					(size 1 1)
					(thickness 0.15)
				)
			)
		)
		(property "License" "Apache-2.0"
			(at 0 0 270)
			(unlocked yes)
			(layer "F.Fab")
			(hide yes)
			(effects
				(font
					(size 1 1)
					(thickness 0.15)
				)
			)
		)
		(property "Author" "Antmicro"
			(at 0 0 270)
			(unlocked yes)
			(layer "F.Fab")
			(hide yes)
			(effects
				(font
					(size 1 1)
					(thickness 0.15)
				)
			)
		)
		(sheetname "/X710-AT2 Misc/")
		(sheetfile "x710-at2-mics.kicad_sch")
		(attr smd)
		(fp_rect
			(start -0.925 -0.47)
			(end 0.925 0.47)
			(stroke
				(width 0.05)
				(type default)
			)
			(fill no)
			(layer "F.CrtYd")
		)
		(fp_line
			(start -0.494 0.248)
			(end -0.494 -0.25)
			(stroke
				(width 0.15)
				(type solid)
			)
			(layer "F.Fab")
		)
		(fp_line
			(start 0.504 0.248)
			(end -0.494 0.248)
			(stroke
				(width 0.15)
				(type solid)
			)
			(layer "F.Fab")
		)
		(fp_line
			(start -0.494 -0.25)
			(end 0.504 -0.25)
			(stroke
				(width 0.15)
				(type solid)
			)
			(layer "F.Fab")
		)
		(fp_line
			(start 0.504 -0.25)
			(end 0.504 0.248)
			(stroke
				(width 0.15)
				(type solid)
			)
			(layer "F.Fab")
		)
		(fp_text user "${REFERENCE}"
			(at -0.939 4.599 270)
			(layer "F.Fab")
			(effects
				(font
					(size 0.7 0.7)
					(thickness 0.15)
				)
				(justify left bottom)
			)
		)
		(fp_text user "Author: Antmicro"
			(at -0.939 3.399 270)
			(layer "F.Fab")
			(effects
				(font
					(size 0.7 0.7)
					(thickness 0.15)
				)
				(justify left bottom)
			)
		)
		(fp_text user "License: Apache-2.0"
			(at -0.939 5.799 270)
			(layer "F.Fab")
			(effects
				(font
					(size 0.7 0.7)
					(thickness 0.15)
				)
				(justify left bottom)
			)
		)
		(pad "1" smd roundrect
			(at -0.48 0 270)
			(size 0.59 0.64)
			(layers "F.Cu" "F.Mask" "F.Paste")
			(roundrect_rratio 0.25)
			(net 23 "GND")
			(pintype "passive")
		)
		(pad "2" smd roundrect
			(at 0.48 0 270)
			(size 0.59 0.64)
			(layers "F.Cu" "F.Mask" "F.Paste")
			(roundrect_rratio 0.25)
			(net 18 "+1V88")
			(pintype "passive")
		)
	)
	(footprint "antmicro-footprints:R_0402_1005Metric"
		(layer "F.Cu")
		(at 127.084 90.309 180)
		(descr "Resistor SMD 0402")
		(tags "resistor SMD 0402")
		(property "Reference" "R119"
			(at 1.084 0.509 180)
			(layer "F.SilkS")
			(effects
				(font
					(size 0.7 0.7)
					(thickness 0.15)
				)
				(justify left bottom)
			)
		)
		(property "Value" "R_8k2_0402"
			(at -1.011843 1.772047 180)
			(layer "F.Fab")
			(effects
				(font
					(size 0.7 0.7)
					(thickness 0.15)
				)
				(justify left bottom)
			)
		)
		(property "Datasheet" "https://www.bourns.com/docs/product-datasheets/cr.pdf"
			(at 0 0 180)
			(layer "F.Fab")
			(hide yes)
			(effects
				(font
					(size 1.27 1.27)
					(thickness 0.15)
				)
			)
		)
		(property "Description" "SMD Chip Resistor"
			(at 0 0 180)
			(layer "F.Fab")
			(hide yes)
			(effects
				(font
					(size 1.27 1.27)
					(thickness 0.15)
				)
			)
		)
		(property "MPN" "CR0402-FX-8201GLF"
			(at 0 0 180)
			(unlocked yes)
			(layer "F.Fab")
			(hide yes)
			(effects
				(font
					(size 1 1)
					(thickness 0.15)
				)
			)
		)
		(property "Manufacturer" "Bourns"
			(at 0 0 180)
			(unlocked yes)
			(layer "F.Fab")
			(hide yes)
			(effects
				(font
					(size 1 1)
					(thickness 0.15)
				)
			)
		)
		(property "License" "Apache-2.0"
			(at 0 0 180)
			(unlocked yes)
			(layer "F.Fab")
			(hide yes)
			(effects
				(font
					(size 1 1)
					(thickness 0.15)
				)
			)
		)
		(property "Author" "Antmicro"
			(at 0 0 180)
			(unlocked yes)
			(layer "F.Fab")
			(hide yes)
			(effects
				(font
					(size 1 1)
					(thickness 0.15)
				)
			)
		)
		(property "Val" "8k2"
			(at 0 0 180)
			(unlocked yes)
			(layer "F.Fab")
			(hide yes)
			(effects
				(font
					(size 1 1)
					(thickness 0.15)
				)
			)
		)
		(property "Tolerance" "1%"
			(at 0 0 180)
			(unlocked yes)
			(layer "F.Fab")
			(hide yes)
			(effects
				(font
					(size 1 1)
					(thickness 0.15)
				)
			)
		)
		(sheetname "/X710-AT2 PCIe/")
		(sheetfile "x710-at2-pcie.kicad_sch")
		(attr smd)
		(fp_rect
			(start -0.925 -0.47)
			(end 0.925 0.47)
			(stroke
				(width 0.05)
				(type default)
			)
			(fill no)
			(layer "F.CrtYd")
		)
		(fp_rect
			(start -0.5 -0.25)
			(end 0.5 0.25)
			(stroke
				(width 0.15)
				(type solid)
			)
			(fill no)
			(layer "F.Fab")
		)
		(fp_text user "License: Apache-2.0"
			(at -0.95 5.169 180)
			(layer "F.Fab")
			(effects
				(font
					(size 0.7 0.7)
					(thickness 0.15)
				)
				(justify left bottom)
			)
		)
		(fp_text user "${REFERENCE}"
			(at -0.95 3.168 180)
			(layer "F.Fab")
			(effects
				(font
					(size 0.7 0.7)
					(thickness 0.15)
				)
				(justify left bottom)
			)
		)
		(fp_text user "Author: Antmicro"
			(at -0.95 4.169 180)
			(layer "F.Fab")
			(effects
				(font
					(size 0.7 0.7)
					(thickness 0.15)
				)
				(justify left bottom)
			)
		)
		(pad "1" smd roundrect
			(at -0.48 0 180)
			(size 0.59 0.64)
			(layers "F.Cu" "F.Mask" "F.Paste")
			(roundrect_rratio 0.25)
			(net 23 "GND")
			(pintype "passive")
		)
		(pad "2" smd roundrect
			(at 0.48 0 180)
			(size 0.59 0.64)
			(layers "F.Cu" "F.Mask" "F.Paste")
			(roundrect_rratio 0.25)
			(net 16 "/X710-AT2 PCIe/PCIe_JTAG.JTCK")
			(pintype "passive")
		)
	)
	(footprint "antmicro-footprints:C_0402_1005Metric"
		(layer "F.Cu")
		(at 136.15 109.150001)
		(descr "Capacitor SMD 0402")
		(tags "capacitor SMD 0402")
		(property "Reference" "C120"
			(at 16.549997 17.25 0)
			(layer "F.SilkS")
			(effects
				(font
					(size 0.7 0.7)
					(thickness 0.15)
				)
			)
		)
		(property "Value" "C_1u_25V_0402"
			(at -1.022927 2.155213 0)
			(layer "F.Fab")
			(effects
				(font
					(size 0.7 0.7)
					(thickness 0.15)
				)
				(justify left bottom)
			)
		)
		(property "Datasheet" "https://www.murata.com/products/productdetail?partno=GRM155R61E105KE11%23"
			(at 0 0 0)
			(layer "F.Fab")
			(hide yes)
			(effects
				(font
					(size 1.27 1.27)
					(thickness 0.15)
				)
			)
		)
		(property "Description" "SMD Multilayer Ceramic Capacitor, 1 µF, 25 V, 0402 [1005 Metric], ± 10%, X5R, GRM Series"
			(at 0 0 0)
			(layer "F.Fab")
			(hide yes)
			(effects
				(font
					(size 1.27 1.27)
					(thickness 0.15)
				)
			)
		)
		(property "MPN" "GRM155R61E105KE11J"
			(at 0 0 0)
			(unlocked yes)
			(layer "F.Fab")
			(hide yes)
			(effects
				(font
					(size 1 1)
					(thickness 0.15)
				)
			)
		)
		(property "Manufacturer" "Murata"
			(at 0 0 0)
			(unlocked yes)
			(layer "F.Fab")
			(hide yes)
			(effects
				(font
					(size 1 1)
					(thickness 0.15)
				)
			)
		)
		(property "License" "Apache-2.0"
			(at 0 0 0)
			(unlocked yes)
			(layer "F.Fab")
			(hide yes)
			(effects
				(font
					(size 1 1)
					(thickness 0.15)
				)
			)
		)
		(property "Author" "Antmicro"
			(at 0 0 0)
			(unlocked yes)
			(layer "F.Fab")
			(hide yes)
			(effects
				(font
					(size 1 1)
					(thickness 0.15)
				)
			)
		)
		(property "Val" "1u"
			(at 0 0 0)
			(unlocked yes)
			(layer "F.Fab")
			(hide yes)
			(effects
				(font
					(size 1 1)
					(thickness 0.15)
				)
			)
		)
		(property "Voltage" "25V"
			(at 0 0 0)
			(unlocked yes)
			(layer "F.Fab")
			(hide yes)
			(effects
				(font
					(size 1 1)
					(thickness 0.15)
				)
			)
		)
		(property "Dielectric" "X5R"
			(at 0 0 0)
			(unlocked yes)
			(layer "F.Fab")
			(hide yes)
			(effects
				(font
					(size 1 1)
					(thickness 0.15)
				)
			)
		)
		(sheetname "/X710 DCDC converters/")
		(sheetfile "DCDC_converters_X710.kicad_sch")
		(attr smd)
		(fp_rect
			(start -0.925 -0.47)
			(end 0.925 0.47)
			(stroke
				(width 0.05)
				(type default)
			)
			(fill no)
			(layer "F.CrtYd")
		)
		(fp_line
			(start -0.494 -0.25)
			(end 0.504 -0.25)
			(stroke
				(width 0.15)
				(type solid)
			)
			(layer "F.Fab")
		)
		(fp_line
			(start -0.494 0.248)
			(end -0.494 -0.25)
			(stroke
				(width 0.15)
				(type solid)
			)
			(layer "F.Fab")
		)
		(fp_line
			(start 0.504 -0.25)
			(end 0.504 0.248)
			(stroke
				(width 0.15)
				(type solid)
			)
			(layer "F.Fab")
		)
		(fp_line
			(start 0.504 0.248)
			(end -0.494 0.248)
			(stroke
				(width 0.15)
				(type solid)
			)
			(layer "F.Fab")
		)
		(fp_text user "License: Apache-2.0"
			(at -0.939 5.799 0)
			(layer "F.Fab")
			(effects
				(font
					(size 0.7 0.7)
					(thickness 0.15)
				)
				(justify left bottom)
			)
		)
		(fp_text user "${REFERENCE}"
			(at -0.939 4.599 0)
			(layer "F.Fab")
			(effects
				(font
					(size 0.7 0.7)
					(thickness 0.15)
				)
				(justify left bottom)
			)
		)
		(fp_text user "Author: Antmicro"
			(at -0.939 3.399 0)
			(layer "F.Fab")
			(effects
				(font
					(size 0.7 0.7)
					(thickness 0.15)
				)
				(justify left bottom)
			)
		)
		(pad "1" smd roundrect
			(at -0.48 0)
			(size 0.59 0.64)
			(layers "F.Cu" "F.Mask" "F.Paste")
			(roundrect_rratio 0.25)
			(net 23 "GND")
			(pintype "passive")
		)
		(pad "2" smd roundrect
			(at 0.48 0)
			(size 0.59 0.64)
			(layers "F.Cu" "F.Mask" "F.Paste")
			(roundrect_rratio 0.25)
			(net 83 "/X710 DCDC converters/VCCD_VCC")
			(pintype "passive")
		)
	)
)
